(kicad_pcb
	(version 20260206)
	(generator "pcbnew")
	(generator_version "10.0")
	(general
		(thickness 1.6)
		(legacy_teardrops no)
	)
	(paper "A4")
	(title_block
		(title "baseboard — 13948-1b.1110WZS1818.brd")
		(comment 1 "Honey Badger (Wiwynn) / footprint 1078 of 2523 (SU1), pads 116-232 of 672")
	)
	(layers
		(0 "F.Cu" signal "TOP")
		(4 "In1.Cu" signal "L2GND")
		(6 "In2.Cu" signal "L3")
		(8 "In3.Cu" signal "L4VCC")
		(10 "In4.Cu" signal "L5VCC")
		(12 "In5.Cu" signal "L6")
		(14 "In6.Cu" signal "L7GND")
		(2 "B.Cu" signal "BOTTOM")
		(9 "F.Adhes" user "F.Adhesive")
		(11 "B.Adhes" user "B.Adhesive")
		(13 "F.Paste" user "Package Geometry/Pastemask Top")
		(15 "B.Paste" user "Package Geometry/Pastemask Bottom")
		(5 "F.SilkS" user "Ref Des/Silkscreen Top")
		(7 "B.SilkS" user "Ref Des/Silkscreen Bottom")
		(1 "F.Mask" user "Board Geometry/Soldermask Top")
		(3 "B.Mask" user "Board Geometry/Soldermask Bottom")
		(17 "Dwgs.User" user "User.Drawings")
		(19 "Cmts.User" user "User.Comments")
		(21 "Eco1.User" user "User.Eco1")
		(23 "Eco2.User" user "User.Eco2")
		(25 "Edge.Cuts" user "Board Geometry/Outline")
		(27 "Margin" user)
		(31 "F.CrtYd" user "Package Geometry/Place Bound Top")
		(29 "B.CrtYd" user "Package Geometry/Place Bound Bottom")
		(35 "F.Fab" user "Ref Des/Assembly Top")
		(33 "B.Fab" user "Ref Des/Assembly Bottom")
	)
	(footprint ""
		(layer "F.Cu")
		(at 114.84991 -94.84995 90)
		(property "Reference" "SU1"
			(at 0 0 90)
			(layer "F.SilkS")
			(hide yes)
			(effects
				(font
					(size 1.27 1.27)
				)
			)
		)
		(property "Value" "SAS3X24RLC1-DB-500021106-GP"
			(at -21.4503 -7.4168 90)
			(unlocked yes)
			(layer "F.Fab")
			(hide yes)
			(effects
				(font
					(size 1.016 1.016)
					(thickness 0.1524)
				)
			)
		)
		(property "Device Type" "BGA672C27H83"
			(at -21.4503 -8.9408 90)
			(unlocked yes)
			(layer "F.Fab")
			(hide yes)
			(effects
				(font
					(size 1.016 1.016)
					(thickness 0.1524)
				)
			)
		)
		(duplicate_pad_numbers_are_jumpers no)
		(pad "AD14" smd circle
			(at 0.500126 10.500106 90)
			(size 0.4572 0.4572)
			(layers "F.Cu" "F.Mask" "F.Paste")
			(net "GB_VDDA")
		)
		(pad "AD15" smd circle
			(at 1.500124 10.500106 90)
			(size 0.4572 0.4572)
			(layers "F.Cu" "F.Mask" "F.Paste")
			(net "Net_1115")
		)
		(pad "AD16" smd circle
			(at 2.500122 10.500106 90)
			(size 0.4572 0.4572)
			(layers "F.Cu" "F.Mask" "F.Paste")
			(net "GB_VDDA")
		)
		(pad "AD17" smd circle
			(at 3.50012 10.500106 90)
			(size 0.4572 0.4572)
			(layers "F.Cu" "F.Mask" "F.Paste")
			(net "Net_1114")
		)
		(pad "AD18" smd circle
			(at 4.500118 10.500106 90)
			(size 0.4572 0.4572)
			(layers "F.Cu" "F.Mask" "F.Paste")
			(net "GB_VDDA")
		)
		(pad "AD19" smd circle
			(at 5.500116 10.500106 90)
			(size 0.4572 0.4572)
			(layers "F.Cu" "F.Mask" "F.Paste")
			(net "Net_1094")
		)
		(pad "AD20" smd circle
			(at 6.500114 10.500106 90)
			(size 0.4572 0.4572)
			(layers "F.Cu" "F.Mask" "F.Paste")
			(net "GB_VDDA")
		)
		(pad "AD21" smd circle
			(at 7.500112 10.500106 90)
			(size 0.4572 0.4572)
			(layers "F.Cu" "F.Mask" "F.Paste")
			(net "Net_1093")
		)
		(pad "AD22" smd circle
			(at 8.50011 10.500106 90)
			(size 0.4572 0.4572)
			(layers "F.Cu" "F.Mask" "F.Paste")
			(net "GND")
		)
		(pad "AD23" smd circle
			(at 9.500108 10.500106 90)
			(size 0.4572 0.4572)
			(layers "F.Cu" "F.Mask" "F.Paste")
			(net "GND")
		)
		(pad "AD24" smd circle
			(at 10.500106 10.500106 90)
			(size 0.508 0.508)
			(layers "F.Cu" "F.Mask" "F.Paste")
			(net "GND")
		)
		(pad "AD25" smd circle
			(at 11.500104 10.500106 90)
			(size 0.508 0.508)
			(layers "F.Cu" "F.Mask" "F.Paste")
			(net "GND")
		)
		(pad "AD26" smd circle
			(at 12.500102 10.500106 90)
			(size 0.508 0.508)
			(layers "F.Cu" "F.Mask" "F.Paste")
			(net "GND")
		)
		(pad "AE1" smd circle
			(at -12.500102 11.500104 90)
			(size 0.508 0.508)
			(layers "F.Cu" "F.Mask" "F.Paste")
			(net "GND")
		)
		(pad "AE2" smd circle
			(at -11.500104 11.500104 90)
			(size 0.508 0.508)
			(layers "F.Cu" "F.Mask" "F.Paste")
			(net "SAS_HDD_TX12_N")
		)
		(pad "AE3" smd circle
			(at -10.500106 11.500104 90)
			(size 0.508 0.508)
			(layers "F.Cu" "F.Mask" "F.Paste")
			(net "SAS_HDD_TX13_P")
		)
		(pad "AE4" smd circle
			(at -9.500108 11.500104 90)
			(size 0.4572 0.4572)
			(layers "F.Cu" "F.Mask" "F.Paste")
			(net "SAS_HDD_TX14_N")
		)
		(pad "AE5" smd circle
			(at -8.50011 11.500104 90)
			(size 0.4572 0.4572)
			(layers "F.Cu" "F.Mask" "F.Paste")
			(net "SAS_HDD_TX15_P")
		)
		(pad "AE6" smd circle
			(at -7.500112 11.500104 90)
			(size 0.4572 0.4572)
			(layers "F.Cu" "F.Mask" "F.Paste")
			(net "3X24_SAS_TX16_N")
		)
		(pad "AE7" smd circle
			(at -6.500114 11.500104 90)
			(size 0.4572 0.4572)
			(layers "F.Cu" "F.Mask" "F.Paste")
			(net "3X24_SAS_TX17_P")
		)
		(pad "AE8" smd circle
			(at -5.500116 11.500104 90)
			(size 0.4572 0.4572)
			(layers "F.Cu" "F.Mask" "F.Paste")
			(net "3X24_SAS_TX18_N")
		)
		(pad "AE9" smd circle
			(at -4.500118 11.500104 90)
			(size 0.4572 0.4572)
			(layers "F.Cu" "F.Mask" "F.Paste")
			(net "3X24_SAS_TX19_P")
		)
		(pad "AE10" smd circle
			(at -3.50012 11.500104 90)
			(size 0.4572 0.4572)
			(layers "F.Cu" "F.Mask" "F.Paste")
			(net "3X24_SAS_TX20_N")
		)
		(pad "AE11" smd circle
			(at -2.500122 11.500104 90)
			(size 0.4572 0.4572)
			(layers "F.Cu" "F.Mask" "F.Paste")
			(net "3X24_SAS_TX21_P")
		)
		(pad "AE12" smd circle
			(at -1.500124 11.500104 90)
			(size 0.4572 0.4572)
			(layers "F.Cu" "F.Mask" "F.Paste")
			(net "3X24_SAS_TX22_N")
		)
		(pad "AE13" smd circle
			(at -0.500126 11.500104 90)
			(size 0.4572 0.4572)
			(layers "F.Cu" "F.Mask" "F.Paste")
			(net "3X24_SAS_TX23_P")
		)
		(pad "AE14" smd circle
			(at 0.500126 11.500104 90)
			(size 0.4572 0.4572)
			(layers "F.Cu" "F.Mask" "F.Paste")
			(net "Net_1113")
		)
		(pad "AE15" smd circle
			(at 1.500124 11.500104 90)
			(size 0.4572 0.4572)
			(layers "F.Cu" "F.Mask" "F.Paste")
			(net "Net_1112")
		)
		(pad "AE16" smd circle
			(at 2.500122 11.500104 90)
			(size 0.4572 0.4572)
			(layers "F.Cu" "F.Mask" "F.Paste")
			(net "Net_1111")
		)
		(pad "AE17" smd circle
			(at 3.50012 11.500104 90)
			(size 0.4572 0.4572)
			(layers "F.Cu" "F.Mask" "F.Paste")
			(net "Net_1110")
		)
		(pad "AE18" smd circle
			(at 4.500118 11.500104 90)
			(size 0.4572 0.4572)
			(layers "F.Cu" "F.Mask" "F.Paste")
			(net "Net_1092")
		)
		(pad "AE19" smd circle
			(at 5.500116 11.500104 90)
			(size 0.4572 0.4572)
			(layers "F.Cu" "F.Mask" "F.Paste")
			(net "Net_1091")
		)
		(pad "AE20" smd circle
			(at 6.500114 11.500104 90)
			(size 0.4572 0.4572)
			(layers "F.Cu" "F.Mask" "F.Paste")
			(net "Net_1090")
		)
		(pad "AE21" smd circle
			(at 7.500112 11.500104 90)
			(size 0.4572 0.4572)
			(layers "F.Cu" "F.Mask" "F.Paste")
			(net "Net_1089")
		)
		(pad "AE22" smd circle
			(at 8.50011 11.500104 90)
			(size 0.4572 0.4572)
			(layers "F.Cu" "F.Mask" "F.Paste")
			(net "GND")
		)
		(pad "AE23" smd circle
			(at 9.500108 11.500104 90)
			(size 0.4572 0.4572)
			(layers "F.Cu" "F.Mask" "F.Paste")
			(net "GND")
		)
		(pad "AE24" smd circle
			(at 10.500106 11.500104 90)
			(size 0.508 0.508)
			(layers "F.Cu" "F.Mask" "F.Paste")
			(net "GND")
		)
		(pad "AE25" smd circle
			(at 11.500104 11.500104 90)
			(size 0.508 0.508)
			(layers "F.Cu" "F.Mask" "F.Paste")
			(net "GND")
		)
		(pad "AE26" smd circle
			(at 12.500102 11.500104 90)
			(size 0.508 0.508)
			(layers "F.Cu" "F.Mask" "F.Paste")
			(net "GND")
		)
		(pad "AF2" smd circle
			(at -11.500104 12.500102 90)
			(size 0.508 0.508)
			(layers "F.Cu" "F.Mask" "F.Paste")
			(net "SAS_HDD_TX12_P")
		)
		(pad "AF3" smd circle
			(at -10.500106 12.500102 90)
			(size 0.508 0.508)
			(layers "F.Cu" "F.Mask" "F.Paste")
			(net "GND")
		)
		(pad "AF4" smd circle
			(at -9.500108 12.500102 90)
			(size 0.4572 0.4572)
			(layers "F.Cu" "F.Mask" "F.Paste")
			(net "SAS_HDD_TX14_P")
		)
		(pad "AF5" smd circle
			(at -8.50011 12.500102 90)
			(size 0.4572 0.4572)
			(layers "F.Cu" "F.Mask" "F.Paste")
			(net "GND")
		)
		(pad "AF6" smd circle
			(at -7.500112 12.500102 90)
			(size 0.4572 0.4572)
			(layers "F.Cu" "F.Mask" "F.Paste")
			(net "3X24_SAS_TX16_P")
		)
		(pad "AF7" smd circle
			(at -6.500114 12.500102 90)
			(size 0.4572 0.4572)
			(layers "F.Cu" "F.Mask" "F.Paste")
			(net "GND")
		)
		(pad "AF8" smd circle
			(at -5.500116 12.500102 90)
			(size 0.4572 0.4572)
			(layers "F.Cu" "F.Mask" "F.Paste")
			(net "3X24_SAS_TX18_P")
		)
		(pad "AF9" smd circle
			(at -4.500118 12.500102 90)
			(size 0.4572 0.4572)
			(layers "F.Cu" "F.Mask" "F.Paste")
			(net "GND")
		)
		(pad "AF10" smd circle
			(at -3.50012 12.500102 90)
			(size 0.4572 0.4572)
			(layers "F.Cu" "F.Mask" "F.Paste")
			(net "3X24_SAS_TX20_P")
		)
		(pad "AF11" smd circle
			(at -2.500122 12.500102 90)
			(size 0.4572 0.4572)
			(layers "F.Cu" "F.Mask" "F.Paste")
			(net "GND")
		)
		(pad "AF12" smd circle
			(at -1.500124 12.500102 90)
			(size 0.4572 0.4572)
			(layers "F.Cu" "F.Mask" "F.Paste")
			(net "3X24_SAS_TX22_P")
		)
		(pad "AF13" smd circle
			(at -0.500126 12.500102 90)
			(size 0.4572 0.4572)
			(layers "F.Cu" "F.Mask" "F.Paste")
			(net "GND")
		)
		(pad "AF14" smd circle
			(at 0.500126 12.500102 90)
			(size 0.4572 0.4572)
			(layers "F.Cu" "F.Mask" "F.Paste")
			(net "Net_1109")
		)
		(pad "AF15" smd circle
			(at 1.500124 12.500102 90)
			(size 0.4572 0.4572)
			(layers "F.Cu" "F.Mask" "F.Paste")
			(net "GND")
		)
		(pad "AF16" smd circle
			(at 2.500122 12.500102 90)
			(size 0.4572 0.4572)
			(layers "F.Cu" "F.Mask" "F.Paste")
			(net "Net_1108")
		)
		(pad "AF17" smd circle
			(at 3.50012 12.500102 90)
			(size 0.4572 0.4572)
			(layers "F.Cu" "F.Mask" "F.Paste")
			(net "GND")
		)
		(pad "AF18" smd circle
			(at 4.500118 12.500102 90)
			(size 0.4572 0.4572)
			(layers "F.Cu" "F.Mask" "F.Paste")
			(net "Net_1088")
		)
		(pad "AF19" smd circle
			(at 5.500116 12.500102 90)
			(size 0.4572 0.4572)
			(layers "F.Cu" "F.Mask" "F.Paste")
			(net "GND")
		)
		(pad "AF20" smd circle
			(at 6.500114 12.500102 90)
			(size 0.4572 0.4572)
			(layers "F.Cu" "F.Mask" "F.Paste")
			(net "Net_1087")
		)
		(pad "AF21" smd circle
			(at 7.500112 12.500102 90)
			(size 0.4572 0.4572)
			(layers "F.Cu" "F.Mask" "F.Paste")
			(net "GND")
		)
		(pad "AF22" smd circle
			(at 8.50011 12.500102 90)
			(size 0.4572 0.4572)
			(layers "F.Cu" "F.Mask" "F.Paste")
			(net "GND")
		)
		(pad "AF23" smd circle
			(at 9.500108 12.500102 90)
			(size 0.4572 0.4572)
			(layers "F.Cu" "F.Mask" "F.Paste")
			(net "EXP_RTRIM_A")
		)
		(pad "AF24" smd circle
			(at 10.500106 12.500102 90)
			(size 0.508 0.508)
			(layers "F.Cu" "F.Mask" "F.Paste")
			(net "EXP_RTRIM_A_N")
		)
		(pad "AF25" smd circle
			(at 11.500104 12.500102 90)
			(size 0.508 0.508)
			(layers "F.Cu" "F.Mask" "F.Paste")
			(net "GND")
		)
		(pad "B1" smd circle
			(at -12.500102 -11.500104 90)
			(size 0.508 0.508)
			(layers "F.Cu" "F.Mask" "F.Paste")
			(net "LSI_PROCMON")
		)
		(pad "B2" smd circle
			(at -11.500104 -11.500104 90)
			(size 0.508 0.508)
			(layers "F.Cu" "F.Mask" "F.Paste")
			(net "EXP_IDDT")
		)
		(pad "B3" smd circle
			(at -10.500106 -11.500104 90)
			(size 0.508 0.508)
			(layers "F.Cu" "F.Mask" "F.Paste")
			(net "GND")
		)
		(pad "B4" smd circle
			(at -9.500108 -11.500104 90)
			(size 0.4572 0.4572)
			(layers "F.Cu" "F.Mask" "F.Paste")
			(net "P1V8_E")
		)
		(pad "B5" smd circle
			(at -8.50011 -11.500104 90)
			(size 0.4572 0.4572)
			(layers "F.Cu" "F.Mask" "F.Paste")
			(net "EXP_XM_CS_N_0")
		)
		(pad "B6" smd circle
			(at -7.500112 -11.500104 90)
			(size 0.4572 0.4572)
			(layers "F.Cu" "F.Mask" "F.Paste")
			(net "XM_DATA5")
		)
		(pad "B7" smd circle
			(at -6.500114 -11.500104 90)
			(size 0.4572 0.4572)
			(layers "F.Cu" "F.Mask" "F.Paste")
			(net "XM_DATA3")
		)
		(pad "B8" smd circle
			(at -5.500116 -11.500104 90)
			(size 0.4572 0.4572)
			(layers "F.Cu" "F.Mask" "F.Paste")
			(net "XM_DATA15")
		)
		(pad "B9" smd circle
			(at -4.500118 -11.500104 90)
			(size 0.4572 0.4572)
			(layers "F.Cu" "F.Mask" "F.Paste")
			(net "XM_DATA10")
		)
		(pad "B10" smd circle
			(at -3.50012 -11.500104 90)
			(size 0.4572 0.4572)
			(layers "F.Cu" "F.Mask" "F.Paste")
			(net "EXP_XM_ADDR_9")
		)
		(pad "B11" smd circle
			(at -2.500122 -11.500104 90)
			(size 0.4572 0.4572)
			(layers "F.Cu" "F.Mask" "F.Paste")
			(net "EXP_XM_ADDR_25")
		)
		(pad "B12" smd circle
			(at -1.500124 -11.500104 90)
			(size 0.4572 0.4572)
			(layers "F.Cu" "F.Mask" "F.Paste")
			(net "EXP_XM_ADDR_22")
		)
		(pad "B13" smd circle
			(at -0.500126 -11.500104 90)
			(size 0.4572 0.4572)
			(layers "F.Cu" "F.Mask" "F.Paste")
			(net "EXP_XM_ADDR_19")
		)
		(pad "B14" smd circle
			(at 0.500126 -11.500104 90)
			(size 0.4572 0.4572)
			(layers "F.Cu" "F.Mask" "F.Paste")
			(net "EXP_XM_ADDR_13")
		)
		(pad "B15" smd circle
			(at 1.500124 -11.500104 90)
			(size 0.4572 0.4572)
			(layers "F.Cu" "F.Mask" "F.Paste")
			(net "EXP_XM_ADDR_1")
		)
		(pad "B16" smd circle
			(at 2.500122 -11.500104 90)
			(size 0.4572 0.4572)
			(layers "F.Cu" "F.Mask" "F.Paste")
			(net "EXP_TACH_IN1")
		)
		(pad "B17" smd circle
			(at 3.50012 -11.500104 90)
			(size 0.4572 0.4572)
			(layers "F.Cu" "F.Mask" "F.Paste")
			(net "EXP_TACH_IN0")
		)
		(pad "B18" smd circle
			(at 4.500118 -11.500104 90)
			(size 0.4572 0.4572)
			(layers "F.Cu" "F.Mask" "F.Paste")
			(net "EXP_GPIO_7")
		)
		(pad "B19" smd circle
			(at 5.500116 -11.500104 90)
			(size 0.4572 0.4572)
			(layers "F.Cu" "F.Mask" "F.Paste")
			(net "EXP_GPIO_5")
		)
		(pad "B20" smd circle
			(at 6.500114 -11.500104 90)
			(size 0.4572 0.4572)
			(layers "F.Cu" "F.Mask" "F.Paste")
			(net "EXP_GPIO_2")
		)
		(pad "B21" smd circle
			(at 7.500112 -11.500104 90)
			(size 0.4572 0.4572)
			(layers "F.Cu" "F.Mask" "F.Paste")
			(net "ICE_TMS")
		)
		(pad "B22" smd circle
			(at 8.50011 -11.500104 90)
			(size 0.4572 0.4572)
			(layers "F.Cu" "F.Mask" "F.Paste")
			(net "SMART_TX")
		)
		(pad "B23" smd circle
			(at 9.500108 -11.500104 90)
			(size 0.4572 0.4572)
			(layers "F.Cu" "F.Mask" "F.Paste")
			(net "SMART_RX")
		)
		(pad "B24" smd circle
			(at 10.500106 -11.500104 90)
			(size 0.508 0.508)
			(layers "F.Cu" "F.Mask" "F.Paste")
			(net "EXP_SIO_CLK_OUT")
		)
		(pad "B25" smd circle
			(at 11.500104 -11.500104 90)
			(size 0.508 0.508)
			(layers "F.Cu" "F.Mask" "F.Paste")
			(net "EXP_I2C_SCL_3")
		)
		(pad "B26" smd circle
			(at 12.500102 -11.500104 90)
			(size 0.508 0.508)
			(layers "F.Cu" "F.Mask" "F.Paste")
			(net "EXP_I2C_SDA_2")
		)
		(pad "C1" smd circle
			(at -12.500102 -10.500106 90)
			(size 0.508 0.508)
			(layers "F.Cu" "F.Mask" "F.Paste")
			(net "JTAG_EXP_TMS")
		)
		(pad "C2" smd circle
			(at -11.500104 -10.500106 90)
			(size 0.508 0.508)
			(layers "F.Cu" "F.Mask" "F.Paste")
			(net "JTAG_EXP_TDI")
		)
		(pad "C3" smd circle
			(at -10.500106 -10.500106 90)
			(size 0.508 0.508)
			(layers "F.Cu" "F.Mask" "F.Paste")
			(net "SOFT_RESET_N")
		)
		(pad "C4" smd circle
			(at -9.500108 -10.500106 90)
			(size 0.4572 0.4572)
			(layers "F.Cu" "F.Mask" "F.Paste")
			(net "EXP_XM_WE_N")
		)
		(pad "C5" smd circle
			(at -8.50011 -10.500106 90)
			(size 0.4572 0.4572)
			(layers "F.Cu" "F.Mask" "F.Paste")
			(net "Net_1128")
		)
		(pad "C6" smd circle
			(at -7.500112 -10.500106 90)
			(size 0.4572 0.4572)
			(layers "F.Cu" "F.Mask" "F.Paste")
			(net "GND")
		)
		(pad "C7" smd circle
			(at -6.500114 -10.500106 90)
			(size 0.4572 0.4572)
			(layers "F.Cu" "F.Mask" "F.Paste")
			(net "XM_DATA7")
		)
		(pad "C8" smd circle
			(at -5.500116 -10.500106 90)
			(size 0.4572 0.4572)
			(layers "F.Cu" "F.Mask" "F.Paste")
			(net "GND")
		)
		(pad "C9" smd circle
			(at -4.500118 -10.500106 90)
			(size 0.4572 0.4572)
			(layers "F.Cu" "F.Mask" "F.Paste")
			(net "XM_DATA11")
		)
		(pad "C10" smd circle
			(at -3.50012 -10.500106 90)
			(size 0.4572 0.4572)
			(layers "F.Cu" "F.Mask" "F.Paste")
			(net "GND")
		)
		(pad "C11" smd circle
			(at -2.500122 -10.500106 90)
			(size 0.4572 0.4572)
			(layers "F.Cu" "F.Mask" "F.Paste")
			(net "EXP_XM_ADDR_4")
		)
		(pad "C12" smd circle
			(at -1.500124 -10.500106 90)
			(size 0.4572 0.4572)
			(layers "F.Cu" "F.Mask" "F.Paste")
			(net "GND")
		)
		(pad "C13" smd circle
			(at -0.500126 -10.500106 90)
			(size 0.4572 0.4572)
			(layers "F.Cu" "F.Mask" "F.Paste")
			(net "EXP_XM_ADDR_18")
		)
		(pad "C14" smd circle
			(at 0.500126 -10.500106 90)
			(size 0.4572 0.4572)
			(layers "F.Cu" "F.Mask" "F.Paste")
			(net "GND")
		)
		(pad "C15" smd circle
			(at 1.500124 -10.500106 90)
			(size 0.4572 0.4572)
			(layers "F.Cu" "F.Mask" "F.Paste")
			(net "EXP_XM_ADDR_0")
		)
		(pad "C16" smd circle
			(at 2.500122 -10.500106 90)
			(size 0.4572 0.4572)
			(layers "F.Cu" "F.Mask" "F.Paste")
			(net "GND")
		)
		(pad "C17" smd circle
			(at 3.50012 -10.500106 90)
			(size 0.4572 0.4572)
			(layers "F.Cu" "F.Mask" "F.Paste")
			(net "EXP_GPIO_13")
		)
		(pad "C18" smd circle
			(at 4.500118 -10.500106 90)
			(size 0.4572 0.4572)
			(layers "F.Cu" "F.Mask" "F.Paste")
			(net "GND")
		)
		(pad "C19" smd circle
			(at 5.500116 -10.500106 90)
			(size 0.4572 0.4572)
			(layers "F.Cu" "F.Mask" "F.Paste")
			(net "EXP_GPIO_1")
		)
		(pad "C20" smd circle
			(at 6.500114 -10.500106 90)
			(size 0.4572 0.4572)
			(layers "F.Cu" "F.Mask" "F.Paste")
			(net "GND")
		)
		(pad "C21" smd circle
			(at 7.500112 -10.500106 90)
			(size 0.4572 0.4572)
			(layers "F.Cu" "F.Mask" "F.Paste")
			(net "ICE_TRST_N")
		)
		(pad "C22" smd circle
			(at 8.50011 -10.500106 90)
			(size 0.4572 0.4572)
			(layers "F.Cu" "F.Mask" "F.Paste")
			(net "GND")
		)
		(pad "C23" smd circle
			(at 9.500108 -10.500106 90)
			(size 0.4572 0.4572)
			(layers "F.Cu" "F.Mask" "F.Paste")
			(net "EXP_I2C_SDA_3")
		)
		(pad "C24" smd circle
			(at 10.500106 -10.500106 90)
			(size 0.508 0.508)
			(layers "F.Cu" "F.Mask" "F.Paste")
			(net "GND")
		)
		(pad "C25" smd circle
			(at 11.500104 -10.500106 90)
			(size 0.508 0.508)
			(layers "F.Cu" "F.Mask" "F.Paste")
			(net "EXP_SDA_0")
		)
		(pad "C26" smd circle
			(at 12.500102 -10.500106 90)
			(size 0.508 0.508)
			(layers "F.Cu" "F.Mask" "F.Paste")
			(net "GND")
		)
		(pad "D1" smd circle
			(at -12.500102 -9.500108 90)
			(size 0.4572 0.4572)
			(layers "F.Cu" "F.Mask" "F.Paste")
			(net "EXP_BLINK_OUT")
		)
		(pad "D2" smd circle
			(at -11.500104 -9.500108 90)
			(size 0.4572 0.4572)
			(layers "F.Cu" "F.Mask" "F.Paste")
			(net "LSI_TRST_N")
		)
	)
)
